# T6G (Grand Teton) — schematic netlist excerpt (pin names and nets, part order shuffled) for the footprints in the layout excerpt that follows; sources: Cadence DE-HDL packaged netlist, KiCad conversion of 04192023_DAF0TMB3IC0_F0TG_MB_C_brd_V02_OCP.brd

C2421  Q_CAP  22UF 4V 20% X6S  pkg C0402  page 74 : A = PVDDCR_SOC_P1 ; B = GND

X8025  TP_TDR_4P_FTS  TP_TDR_4P_DIP EMPTY  pkg TH  page 260
  S1  = TDR_DIFF_85_IN5_DP
  P1  = T1_GND
  P2  = T1_GND
  S2  = TDR_DIFF_85_IN5_DN

(kicad_pcb
	(version 20260206)
	(generator "pcbnew")
	(generator_version "10.0")
	(general
		(thickness 1.6)
		(legacy_teardrops no)
	)
	(paper "A4")
	(title_block
		(title "04192023_DAF0TMB3IC0_F0TG_MB_C_brd_V02_OCP.brd")
		(comment 1 "Grand Teton / footprints 5681-5682 of 8354")
	)
	(layers
		(0 "F.Cu" signal "TOP")
		(4 "In1.Cu" signal "GND")
		(6 "In2.Cu" signal "IN1")
		(8 "In3.Cu" signal "GND1")
		(10 "In4.Cu" signal "IN2")
		(12 "In5.Cu" signal "GND2")
		(14 "In6.Cu" signal "IN3")
		(16 "In7.Cu" signal "GND3")
		(18 "In8.Cu" signal "VCC")
		(20 "In9.Cu" signal "VCC1")
		(22 "In10.Cu" signal "GND4")
		(24 "In11.Cu" signal "IN4")
		(26 "In12.Cu" signal "GND5")
		(28 "In13.Cu" signal "IN5")
		(30 "In14.Cu" signal "GND6")
		(32 "In15.Cu" signal "IN6")
		(34 "In16.Cu" signal "GND7")
		(2 "B.Cu" signal "BOTTOM")
		(9 "F.Adhes" user "F.Adhesive")
		(11 "B.Adhes" user "B.Adhesive")
		(13 "F.Paste" user "Package Geometry/Pastemask Top")
		(15 "B.Paste" user "Package Geometry/Pastemask Bottom")
		(5 "F.SilkS" user "Ref Des/Silkscreen Top")
		(7 "B.SilkS" user "Ref Des/Silkscreen Bottom")
		(1 "F.Mask" user "Board Geometry/Soldermask Top")
		(3 "B.Mask" user "Board Geometry/Soldermask Bottom")
		(17 "Dwgs.User" user "User.Drawings")
		(19 "Cmts.User" user "User.Comments")
		(21 "Eco1.User" user "User.Eco1")
		(23 "Eco2.User" user "User.Eco2")
		(25 "Edge.Cuts" user "Board Geometry/Outline")
		(27 "Margin" user)
		(31 "F.CrtYd" user "Package Geometry/Place Bound Top")
		(29 "B.CrtYd" user "Package Geometry/Place Bound Bottom")
		(35 "F.Fab" user "Ref Des/Assembly Top")
		(33 "B.Fab" user "Ref Des/Assembly Bottom")
	)
	(footprint ""
		(layer "B.Cu")
		(at 504.058428 7.571994 90)
		(property "Reference" "X8025"
			(at 0.93726 -1.53035 270)
			(unlocked yes)
			(layer "B.SilkS")
			(effects
				(font
					(size 0.7874 0.5842)
					(thickness 0.1524)
				)
				(justify left mirror)
			)
		)
		(property "Value" ""
			(at 0 0 90)
			(layer "B.Fab")
			(effects
				(font
					(size 1.27 1.27)
				)
				(justify mirror)
			)
		)
		(property "Device Type" "TP_TDR_4P_FTS_TH-TP_TDR_4P_DIP,EMPTY,TP15"
			(at -1.30175 1.27 0)
			(unlocked yes)
			(layer "B.Fab")
			(hide yes)
			(effects
				(font
					(size 0.635 0.4064)
					(thickness 0.1524)
				)
				(justify mirror)
			)
		)
		(property "User Part Number" "N_A"
			(at -1.30175 1.27 0)
			(unlocked yes)
			(layer "Cmts.User")
			(hide yes)
			(effects
				(font
					(size 0.635 0.4064)
					(thickness 0.1524)
				)
				(justify mirror)
			)
		)
		(duplicate_pad_numbers_are_jumpers no)
		(fp_line
			(start 0 -1.27)
			(end 0 -0.635)
			(stroke
				(width 0.1524)
				(type default)
			)
			(layer "B.SilkS")
		)
		(fp_line
			(start -2.54 -1.27)
			(end 0 -1.27)
			(stroke
				(width 0.1524)
				(type default)
			)
			(layer "B.SilkS")
		)
		(fp_line
			(start -2.54 -1.1303)
			(end -2.54 -1.27)
			(stroke
				(width 0.1524)
				(type default)
			)
			(layer "B.SilkS")
		)
		(fp_line
			(start 0 0.635)
			(end 0 1.905)
			(stroke
				(width 0.1524)
				(type default)
			)
			(layer "B.SilkS")
		)
		(fp_line
			(start -2.54 1.4097)
			(end -2.54 1.1303)
			(stroke
				(width 0.1524)
				(type default)
			)
			(layer "B.SilkS")
		)
		(fp_line
			(start 0 3.175)
			(end 0 3.81)
			(stroke
				(width 0.1524)
				(type default)
			)
			(layer "B.SilkS")
		)
		(fp_line
			(start 0 3.81)
			(end -2.54 3.81)
			(stroke
				(width 0.1524)
				(type default)
			)
			(layer "B.SilkS")
		)
		(fp_line
			(start -2.54 3.81)
			(end -2.54 3.6703)
			(stroke
				(width 0.1524)
				(type default)
			)
			(layer "B.SilkS")
		)
		(fp_poly
			(pts
				(xy 0.761746 0) (xy 2.285746 -0.762) (xy 2.285746 0.762)
			)
			(stroke
				(width 0)
				(type default)
			)
			(fill yes)
			(layer "B.SilkS")
		)
		(fp_line
			(start 0 -1.27)
			(end 0 3.81)
			(stroke
				(width 0.1)
				(type default)
			)
			(layer "B.Fab")
		)
		(fp_line
			(start -2.54 -1.27)
			(end 0 -1.27)
			(stroke
				(width 0.1)
				(type default)
			)
			(layer "B.Fab")
		)
		(fp_line
			(start 0 3.81)
			(end -2.54 3.81)
			(stroke
				(width 0.1)
				(type default)
			)
			(layer "B.Fab")
		)
		(fp_line
			(start -2.54 3.81)
			(end -2.54 -1.27)
			(stroke
				(width 0.1)
				(type default)
			)
			(layer "B.Fab")
		)
		(fp_poly
			(pts
				(xy 0.761746 0) (xy 2.285746 -0.762) (xy 2.285746 0.762)
			)
			(stroke
				(width 0)
				(type default)
			)
			(fill yes)
			(layer "B.Fab")
		)
		(pad "1" thru_hole circle
			(at 0 0 270)
			(size 1.0033 1.0033)
			(drill 0.249936)
			(layers "*.Cu" "*.Mask")
			(remove_unused_layers no)
			(net "TDR_DIFF_85_IN5_DP")
			(clearance 0.10795)
			(padstack
				(mode front_inner_back)
				(layer "Inner"
					(shape circle)
					(size 0.8001 0.8001)
					(clearance 0.1524)
				)
				(layer "B.Cu"
					(shape circle)
					(size 1.0033 1.0033)
					(thermal_gap 0.10795)
					(clearance 0.10795)
				)
			)
		)
		(pad "2" thru_hole circle
			(at -2.54 0 270)
			(size 1.9939 1.9939)
			(drill 0.249936)
			(layers "*.Cu" "*.Mask")
			(remove_unused_layers no)
			(net "T1_GND")
			(clearance 0.10795)
			(padstack
				(mode front_inner_back)
				(layer "Inner"
					(shape circle)
					(size 0.8001 0.8001)
					(clearance 0.1524)
				)
				(layer "B.Cu"
					(shape circle)
					(size 1.9939 1.9939)
					(thermal_gap 0.10795)
					(clearance 0.10795)
				)
			)
		)
		(pad "3" thru_hole circle
			(at -2.54 2.54 270)
			(size 1.9939 1.9939)
			(drill 0.249936)
			(layers "*.Cu" "*.Mask")
			(remove_unused_layers no)
			(net "T1_GND")
			(clearance 0.10795)
			(padstack
				(mode front_inner_back)
				(layer "Inner"
					(shape circle)
					(size 0.8001 0.8001)
					(clearance 0.1524)
				)
				(layer "B.Cu"
					(shape circle)
					(size 1.9939 1.9939)
					(thermal_gap 0.10795)
					(clearance 0.10795)
				)
			)
		)
		(pad "4" thru_hole circle
			(at 0 2.54 270)
			(size 1.0033 1.0033)
			(drill 0.249936)
			(layers "*.Cu" "*.Mask")
			(remove_unused_layers no)
			(net "TDR_DIFF_85_IN5_DN")
			(clearance 0.10795)
			(padstack
				(mode front_inner_back)
				(layer "Inner"
					(shape circle)
					(size 0.8001 0.8001)
					(clearance 0.1524)
				)
				(layer "B.Cu"
					(shape circle)
					(size 1.0033 1.0033)
					(thermal_gap 0.10795)
					(clearance 0.10795)
				)
			)
		)
	)
	(footprint ""
		(layer "B.Cu")
		(at 102.253034 -254.504952 -60)
		(property "Reference" "C2421"
			(at 0 0 120)
			(layer "B.SilkS")
			(hide yes)
			(effects
				(font
					(size 1.27 1.27)
				)
				(justify mirror)
			)
		)
		(property "Value" ""
			(at 0 0 120)
			(layer "B.Fab")
			(effects
				(font
					(size 1.27 1.27)
				)
				(justify mirror)
			)
		)
		(duplicate_pad_numbers_are_jumpers no)
		(fp_line
			(start -0.787516 0.406438)
			(end 0.787425 0.40652)
			(stroke
				(width 0.1524)
				(type default)
			)
			(layer "B.SilkS")
		)
		(fp_line
			(start -0.787425 -0.40652)
			(end -0.787516 0.406438)
			(stroke
				(width 0.1524)
				(type default)
			)
			(layer "B.SilkS")
		)
		(fp_line
			(start 0.787425 0.40652)
			(end 0.787516 -0.406438)
			(stroke
				(width 0.1524)
				(type default)
			)
			(layer "B.SilkS")
		)
		(fp_line
			(start 0.787516 -0.406438)
			(end -0.787425 -0.40652)
			(stroke
				(width 0.1524)
				(type default)
			)
			(layer "B.SilkS")
		)
		(fp_line
			(start -0.679568 0.304811)
			(end -0.120258 0.304812)
			(stroke
				(width 0.1)
				(type default)
			)
			(layer "B.Fab")
		)
		(fp_line
			(start -0.120258 0.304812)
			(end -0.120334 0.279545)
			(stroke
				(width 0.1)
				(type default)
			)
			(layer "B.Fab")
		)
		(fp_line
			(start -0.120334 0.279545)
			(end 0.120587 0.279326)
			(stroke
				(width 0.1)
				(type default)
			)
			(layer "B.Fab")
		)
		(fp_line
			(start 0.120536 0.304813)
			(end 0.6795 0.304908)
			(stroke
				(width 0.1)
				(type default)
			)
			(layer "B.Fab")
		)
		(fp_line
			(start 0.120587 0.279326)
			(end 0.120536 0.304813)
			(stroke
				(width 0.1)
				(type default)
			)
			(layer "B.Fab")
		)
		(fp_line
			(start -0.6795 -0.304908)
			(end -0.679568 0.304811)
			(stroke
				(width 0.1)
				(type default)
			)
			(layer "B.Fab")
		)
		(fp_line
			(start 0.6795 0.304908)
			(end 0.679475 -0.305158)
			(stroke
				(width 0.1)
				(type default)
			)
			(layer "B.Fab")
		)
		(fp_line
			(start -0.120587 -0.279326)
			(end -0.120536 -0.304813)
			(stroke
				(width 0.1)
				(type default)
			)
			(layer "B.Fab")
		)
		(fp_line
			(start -0.120536 -0.304813)
			(end -0.6795 -0.304908)
			(stroke
				(width 0.1)
				(type default)
			)
			(layer "B.Fab")
		)
		(fp_line
			(start 0.120554 -0.279418)
			(end -0.120587 -0.279326)
			(stroke
				(width 0.1)
				(type default)
			)
			(layer "B.Fab")
		)
		(fp_line
			(start 0.120732 -0.305125)
			(end 0.120554 -0.279418)
			(stroke
				(width 0.1)
				(type default)
			)
			(layer "B.Fab")
		)
		(fp_line
			(start 0.679475 -0.305158)
			(end 0.120732 -0.305125)
			(stroke
				(width 0.1)
				(type default)
			)
			(layer "B.Fab")
		)
		(pad "1" smd circle
			(at 0.40005 0 120)
			(size 0 0)
			(layers "B.Cu" "B.Mask" "B.Paste")
			(net "PVDDCR_SOC_P1")
		)
		(pad "2" smd circle
			(at -0.40005 0 120)
			(size 0 0)
			(layers "B.Cu" "B.Mask" "B.Paste")
			(net "GND")
		)
	)
)
